#ISCELL
  mstr_misc dns *
  *
#ISCELL
  pure_quanta quanta_title_block_c *
  *
#ISCELL
  logical_power universal_gnd *
  page188_i20
#CELL
  pure_quanta q_res *
  page188_i21
#CELL
  pure_quanta q_res *
  page188_i22
#ISCELL
  logical_power universal_power *
  page188_i23
#ISCELL
  standard offpage *
  page188_i25
#ISCELL
  standard offpage *
  page188_i26
#ISCELL
  logical_power universal_gnd *
  page188_i30
#CELL
  pure_quanta q_res *
  page188_i31
#ISCELL
  standard offpage *
  page188_i33
#CELL
  pure_quanta q_res *
  page188_i36
#ISCELL
  logical_power universal_gnd *
  page188_i37
#ISCELL
  standard offpage *
  page188_i38
#ISCELL
  logical_power universal_power *
  page188_i39
#ISCELL
  logical_power universal_gnd *
  page188_i42
#CELL
  pure_quanta q_res *
  page188_i43
#CELL
  pure_quanta q_res *
  page188_i44
#ISCELL
  standard offpage *
  page188_i45
#ISCELL
  logical_power universal_power *
  page188_i46
#CELL
  pure_quanta q_res *
  page188_i47
#ISCELL
  logical_power universal_gnd *
  page188_i49
#CELL
  pure_quanta q_res *
  page188_i50
#ISCELL
  standard offpage *
  page188_i51
#ISCELL
  logical_power universal_power *
  page188_i52
#CELL
  pure_quanta q_res *
  page188_i57
#ISCELL
  standard offpage *
  page188_i59
#ISCELL
  logical_power universal_power *
  page188_i60
#ISCELL
  logical_power universal_gnd *
  page188_i62
#CELL
  pure_quanta q_res *
  page188_i63
#CELL
  pure_quanta q_res *
  page188_i64
#ISCELL
  standard offpage *
  page188_i66
#ISCELL
  logical_power universal_power *
  page188_i67
#ISCELL
  logical_power universal_gnd *
  page188_i69
#CELL
  pure_quanta q_res *
  page188_i70
#CELL
  pure_quanta q_res *
  page188_i71
#ISCELL
  standard offpage *
  page188_i72
#ISCELL
  logical_power universal_power *
  page188_i73
#ISCELL
  logical_power universal_gnd *
  page188_i75
#CELL
  pure_quanta q_res *
  page188_i76
#CELL
  pure_quanta q_res *
  page188_i77
